# S9S_MB_2U (Grand Teton) — schematic netlist excerpt (pin names and nets, part order shuffled) for the footprints in the layout excerpt that follows; sources: Cadence DE-HDL packaged netlist, KiCad conversion of 03242023_DA0F0TMBIJ0_F0T_Motherboard_J_brd_V01_OCP.brd

R4146  Q_RES  33.2 1% CHIP  pkg 0402LF  page 215 : A = GPU_3V3IO_RSVD3_FFU_ISO ; B = GPU_3V3IO_RSVD3_FFU_ISO_R
H103  HOLE  EMPTY  pkg TH  page 311 : \1\ = GND
R4191  Q_RES  1K 1% CHIP  pkg 0402LF  page 170 : A = U270_0_ADD2 ; B = GND

(kicad_pcb
	(version 20260206)
	(generator "pcbnew")
	(generator_version "10.0")
	(general
		(thickness 1.6)
		(legacy_teardrops no)
	)
	(paper "A4")
	(title_block
		(title "03242023_DA0F0TMBIJ0_F0T_Motherboard_J_brd_V01_OCP.brd")
		(comment 1 "Grand Teton / footprints 1323-1325 of 6105")
	)
	(layers
		(0 "F.Cu" signal "TOP")
		(4 "In1.Cu" signal "GND")
		(6 "In2.Cu" signal "IN1")
		(8 "In3.Cu" signal "GND1")
		(10 "In4.Cu" signal "IN2")
		(12 "In5.Cu" signal "GND2")
		(14 "In6.Cu" signal "IN3")
		(16 "In7.Cu" signal "GND3")
		(18 "In8.Cu" signal "VCC")
		(20 "In9.Cu" signal "VCC1")
		(22 "In10.Cu" signal "GND4")
		(24 "In11.Cu" signal "IN4")
		(26 "In12.Cu" signal "GND5")
		(28 "In13.Cu" signal "IN5")
		(30 "In14.Cu" signal "GND6")
		(32 "In15.Cu" signal "IN6")
		(34 "In16.Cu" signal "GND7")
		(2 "B.Cu" signal "BOTTOM")
		(9 "F.Adhes" user "F.Adhesive")
		(11 "B.Adhes" user "B.Adhesive")
		(13 "F.Paste" user "Package Geometry/Pastemask Top")
		(15 "B.Paste" user "Package Geometry/Pastemask Bottom")
		(5 "F.SilkS" user "Ref Des/Silkscreen Top")
		(7 "B.SilkS" user "Ref Des/Silkscreen Bottom")
		(1 "F.Mask" user "Board Geometry/Soldermask Top")
		(3 "B.Mask" user "Board Geometry/Soldermask Bottom")
		(17 "Dwgs.User" user "User.Drawings")
		(19 "Cmts.User" user "User.Comments")
		(21 "Eco1.User" user "User.Eco1")
		(23 "Eco2.User" user "User.Eco2")
		(25 "Edge.Cuts" user "Board Geometry/Outline")
		(27 "Margin" user)
		(31 "F.CrtYd" user "Package Geometry/Place Bound Top")
		(29 "B.CrtYd" user "Package Geometry/Place Bound Bottom")
		(35 "F.Fab" user "Ref Des/Assembly Top")
		(33 "B.Fab" user "Ref Des/Assembly Bottom")
	)
	(footprint ""
		(layer "F.Cu")
		(at 369.368578 -413.90951 -90)
		(property "Reference" "R4191"
			(at 0 0 270)
			(layer "F.SilkS")
			(hide yes)
			(effects
				(font
					(size 1.27 1.27)
				)
			)
		)
		(property "Value" ""
			(at 0 0 270)
			(layer "F.Fab")
			(effects
				(font
					(size 1.27 1.27)
				)
			)
		)
		(duplicate_pad_numbers_are_jumpers no)
		(fp_line
			(start -0.7874 0.4064)
			(end -0.7874 -0.4064)
			(stroke
				(width 0.1524)
				(type default)
			)
			(layer "F.SilkS")
		)
		(fp_line
			(start 0.7874 0.4064)
			(end -0.7874 0.4064)
			(stroke
				(width 0.1524)
				(type default)
			)
			(layer "F.SilkS")
		)
		(fp_line
			(start -0.7874 -0.4064)
			(end 0.7874 -0.4064)
			(stroke
				(width 0.1524)
				(type default)
			)
			(layer "F.SilkS")
		)
		(fp_line
			(start 0.7874 -0.4064)
			(end 0.7874 0.4064)
			(stroke
				(width 0.1524)
				(type default)
			)
			(layer "F.SilkS")
		)
		(fp_line
			(start -0.67945 0.3048)
			(end -0.67945 -0.305054)
			(stroke
				(width 0.1)
				(type default)
			)
			(layer "F.Fab")
		)
		(fp_line
			(start -0.12065 0.3048)
			(end -0.67945 0.3048)
			(stroke
				(width 0.1)
				(type default)
			)
			(layer "F.Fab")
		)
		(fp_line
			(start 0.120396 0.3048)
			(end 0.120396 0.2794)
			(stroke
				(width 0.1)
				(type default)
			)
			(layer "F.Fab")
		)
		(fp_line
			(start 0.67945 0.3048)
			(end 0.120396 0.3048)
			(stroke
				(width 0.1)
				(type default)
			)
			(layer "F.Fab")
		)
		(fp_line
			(start -0.12065 0.2794)
			(end -0.12065 0.3048)
			(stroke
				(width 0.1)
				(type default)
			)
			(layer "F.Fab")
		)
		(fp_line
			(start 0.120396 0.2794)
			(end -0.12065 0.2794)
			(stroke
				(width 0.1)
				(type default)
			)
			(layer "F.Fab")
		)
		(fp_line
			(start -0.12065 -0.2794)
			(end 0.12065 -0.2794)
			(stroke
				(width 0.1)
				(type default)
			)
			(layer "F.Fab")
		)
		(fp_line
			(start 0.12065 -0.2794)
			(end 0.12065 -0.3048)
			(stroke
				(width 0.1)
				(type default)
			)
			(layer "F.Fab")
		)
		(fp_line
			(start 0.12065 -0.3048)
			(end 0.67945 -0.3048)
			(stroke
				(width 0.1)
				(type default)
			)
			(layer "F.Fab")
		)
		(fp_line
			(start 0.67945 -0.3048)
			(end 0.67945 0.3048)
			(stroke
				(width 0.1)
				(type default)
			)
			(layer "F.Fab")
		)
		(fp_line
			(start -0.67945 -0.305054)
			(end -0.12065 -0.305054)
			(stroke
				(width 0.1)
				(type default)
			)
			(layer "F.Fab")
		)
		(fp_line
			(start -0.12065 -0.305054)
			(end -0.12065 -0.2794)
			(stroke
				(width 0.1)
				(type default)
			)
			(layer "F.Fab")
		)
		(pad "1" smd circle
			(at -0.40005 0 270)
			(size 0 0)
			(layers "F.Cu" "F.Mask" "F.Paste")
			(net "U270_0_ADD2")
		)
		(pad "2" smd circle
			(at 0.40005 0 270)
			(size 0 0)
			(layers "F.Cu" "F.Mask" "F.Paste")
			(net "GND")
		)
	)
	(footprint ""
		(layer "F.Cu")
		(at 201.00036 -114.264948 180)
		(property "Reference" "R4146"
			(at 0 0 180)
			(layer "F.SilkS")
			(hide yes)
			(effects
				(font
					(size 1.27 1.27)
				)
			)
		)
		(property "Value" ""
			(at 0 0 180)
			(layer "F.Fab")
			(effects
				(font
					(size 1.27 1.27)
				)
			)
		)
		(duplicate_pad_numbers_are_jumpers no)
		(fp_line
			(start 0.7874 0.4064)
			(end -0.7874 0.4064)
			(stroke
				(width 0.1524)
				(type default)
			)
			(layer "F.SilkS")
		)
		(fp_line
			(start 0.7874 -0.4064)
			(end 0.7874 0.4064)
			(stroke
				(width 0.1524)
				(type default)
			)
			(layer "F.SilkS")
		)
		(fp_line
			(start -0.7874 0.4064)
			(end -0.7874 -0.4064)
			(stroke
				(width 0.1524)
				(type default)
			)
			(layer "F.SilkS")
		)
		(fp_line
			(start -0.7874 -0.4064)
			(end 0.7874 -0.4064)
			(stroke
				(width 0.1524)
				(type default)
			)
			(layer "F.SilkS")
		)
		(fp_line
			(start 0.67945 0.3048)
			(end 0.120396 0.3048)
			(stroke
				(width 0.1)
				(type default)
			)
			(layer "F.Fab")
		)
		(fp_line
			(start 0.67945 -0.3048)
			(end 0.67945 0.3048)
			(stroke
				(width 0.1)
				(type default)
			)
			(layer "F.Fab")
		)
		(fp_line
			(start 0.12065 -0.2794)
			(end 0.12065 -0.3048)
			(stroke
				(width 0.1)
				(type default)
			)
			(layer "F.Fab")
		)
		(fp_line
			(start 0.12065 -0.3048)
			(end 0.67945 -0.3048)
			(stroke
				(width 0.1)
				(type default)
			)
			(layer "F.Fab")
		)
		(fp_line
			(start 0.120396 0.3048)
			(end 0.120396 0.2794)
			(stroke
				(width 0.1)
				(type default)
			)
			(layer "F.Fab")
		)
		(fp_line
			(start 0.120396 0.2794)
			(end -0.12065 0.2794)
			(stroke
				(width 0.1)
				(type default)
			)
			(layer "F.Fab")
		)
		(fp_line
			(start -0.12065 0.3048)
			(end -0.67945 0.3048)
			(stroke
				(width 0.1)
				(type default)
			)
			(layer "F.Fab")
		)
		(fp_line
			(start -0.12065 0.2794)
			(end -0.12065 0.3048)
			(stroke
				(width 0.1)
				(type default)
			)
			(layer "F.Fab")
		)
		(fp_line
			(start -0.12065 -0.2794)
			(end 0.12065 -0.2794)
			(stroke
				(width 0.1)
				(type default)
			)
			(layer "F.Fab")
		)
		(fp_line
			(start -0.12065 -0.305054)
			(end -0.12065 -0.2794)
			(stroke
				(width 0.1)
				(type default)
			)
			(layer "F.Fab")
		)
		(fp_line
			(start -0.67945 0.3048)
			(end -0.67945 -0.305054)
			(stroke
				(width 0.1)
				(type default)
			)
			(layer "F.Fab")
		)
		(fp_line
			(start -0.67945 -0.305054)
			(end -0.12065 -0.305054)
			(stroke
				(width 0.1)
				(type default)
			)
			(layer "F.Fab")
		)
		(pad "1" smd circle
			(at -0.40005 0 180)
			(size 0 0)
			(layers "F.Cu" "F.Mask" "F.Paste")
			(net "GPU_3V3IO_RSVD3_FFU_ISO")
		)
		(pad "2" smd circle
			(at 0.40005 0 180)
			(size 0 0)
			(layers "F.Cu" "F.Mask" "F.Paste")
			(net "GPU_3V3IO_RSVD3_FFU_ISO_R")
		)
	)
	(footprint ""
		(layer "F.Cu")
		(at 203.399898 -22.29993)
		(property "Reference" "H103"
			(at -4.60502 -5.580888 0)
			(unlocked yes)
			(layer "F.SilkS")
			(effects
				(font
					(size 0.7874 0.5842)
					(thickness 0.1524)
				)
				(justify left)
			)
		)
		(property "Value" ""
			(at 0 0 0)
			(layer "F.Fab")
			(effects
				(font
					(size 1.27 1.27)
				)
			)
		)
		(duplicate_pad_numbers_are_jumpers no)
		(pad "1" thru_hole circle
			(at 0 0)
			(size 10.0076 10.0076)
			(drill 5.6134)
			(layers "*.Cu" "*.Mask")
			(remove_unused_layers no)
			(net "GND")
			(clearance -1.9431)
		)
	)
)
